FILE_TYPE = CONNECTIVITY;
{Allegro Design Entry HDL 17.2-2016 S081 (4005846) 1/11/2022}
"PAGE_NUMBER" = 112;
0"NC";
1"P3V3_AUX\g";
2"P12V_S3_AUX_CPU1_NVDIMM\g";
3"P3V3_AUX\g";
4"P12V_S3_AUX_CPU1_NVDIMM\g";
5"GND\g";
6"GND\g";
7"GND\g";
8"GND\g";
9"GND\g";
10"M_H_CPU1_SA_DQ<31:0>";
11"M_H_CPU1_SA_CB<7:0>";
12"M_H_CPU1_SB_CB<7:0>";
13"M_H_CPU1_SB_CA<6:0>";
14"M_H_CPU1_SA_CA<6:0>";
15"M_H_CPU1_SB_DQ<31:0>";
16"M_H_CPU1_SB_DQS_DP<9:0>";
17"M_H_CPU1_SA_DQS_DP<9:0>";
18"M_H_CPU1_SB_DQS_DN<9:0>";
19"M_H_CPU1_SA_DQS_DN<9:0>";
20"M_H_CPU1_SB_DQ<2>";
21"PWRGD_CHH_CPU1_DIMM1";
22"TP_CHH_CPU1_DIMM1_FRU_6";
23"TP_CHH_CPU1_DIMM1_FRU_4";
24"TP_CHH_CPU1_DIMM1_FRU_3";
25"TP_CHH_CPU1_DIMM1_FRU_2";
26"TP_CHH_CPU1_DIMM1_FRU_1";
27"TP_CHH_CPU1_DIMM1_FRU_0";
28"I3C_SPD_DDREFGH_CPU1_LVC1_SCL";
29"I3C_SPD_DDREFGH_CPU1_LVC1_SCL_R7";
30"M_H_CPU1_ALERT_N";
31"RST_M_GH_CPU1_FPGA_N";
32"PD_CHH_CPU1_DIMM1_SAA";
33"I3C_SPD_DDREFGH_CPU1_LVC1_SDA";
34"M_H_CPU1_SB_CB<1>";
35"M_H_CPU1_SA_DQS_DN<9>";
36"M_H_CPU1_SA_DQS_DN<8>";
37"M_H_CPU1_SA_DQS_DN<7>";
38"M_H_CPU1_SA_DQS_DN<6>";
39"M_H_CPU1_SA_DQS_DN<5>";
40"M_H_CPU1_SA_DQS_DN<4>";
41"M_H_CPU1_SA_DQS_DN<3>";
42"M_H_CPU1_SA_DQS_DN<2>";
43"M_H_CPU1_SA_DQS_DN<1>";
44"M_H_CPU1_SA_DQS_DN<0>";
45"M_H_CPU1_SB_DQS_DN<9>";
46"M_H_CPU1_SB_DQS_DN<8>";
47"M_H_CPU1_SB_DQS_DN<7>";
48"M_H_CPU1_SB_DQS_DN<6>";
49"M_H_CPU1_SB_DQS_DN<4>";
50"M_H_CPU1_SB_DQS_DN<5>";
51"M_H_CPU1_SB_DQS_DN<3>";
52"M_H_CPU1_SB_DQS_DN<2>";
53"M_H_CPU1_SB_DQS_DN<1>";
54"M_H_CPU1_SB_DQS_DN<0>";
55"M_H_CPU1_SA_DQS_DP<9>";
56"M_H_CPU1_SA_DQS_DP<8>";
57"M_H_CPU1_SA_DQS_DP<7>";
58"M_H_CPU1_SA_DQS_DP<6>";
59"M_H_CPU1_SA_DQS_DP<5>";
60"M_H_CPU1_SA_DQS_DP<4>";
61"M_H_CPU1_SA_DQS_DP<3>";
62"M_H_CPU1_SA_DQS_DP<2>";
63"M_H_CPU1_SA_DQS_DP<1>";
64"M_H_CPU1_SA_DQS_DP<0>";
65"M_H_CPU1_SB_DQS_DP<9>";
66"M_H_CPU1_SB_DQS_DP<8>";
67"M_H_CPU1_SB_DQS_DP<7>";
68"M_H_CPU1_SB_DQS_DP<6>";
69"M_H_CPU1_SB_DQS_DP<5>";
70"M_H_CPU1_SB_DQS_DP<4>";
71"M_H_CPU1_SB_DQS_DP<3>";
72"M_H_CPU1_SB_DQS_DP<2>";
73"M_H_CPU1_SB_DQS_DP<1>";
74"M_H_CPU1_SB_DQS_DP<0>";
75"M_H_CPU1_SA_CB<0>";
76"M_H_CPU1_SA_CA<0>";
77"M_H_CPU1_SB_CA<4>";
78"M_H_CPU1_SB_CS_N<1>";
79"M_H_CPU1_SB_CS_N<0>";
80"M_H_CPU1_SB_DQ<23>";
81"M_H_CPU1_SB_DQ<22>";
82"M_H_CPU1_SB_DQ<21>";
83"M_H_CPU1_SB_CB<4>";
84"M_H_CPU1_SB_DQ<27>";
85"M_H_CPU1_SB_DQ<13>";
86"TP_CHH_CPU1_DIMM1_FRU_5";
87"M_H_CPU1_SB_PAR";
88"M_H_CPU1_SA_PAR";
89"M_H_CPU1_SB_RSP<0>";
90"M_H_CPU1_SA_RSP<0>";
91"M_H_CPU1_SB_DQ<0>";
92"M_H_CPU1_SB_DQ<1>";
93"M_H_CPU1_SB_DQ<3>";
94"M_H_CPU1_SB_DQ<4>";
95"M_H_CPU1_SB_DQ<5>";
96"M_H_CPU1_SB_DQ<6>";
97"M_H_CPU1_SB_DQ<7>";
98"M_H_CPU1_SB_DQ<8>";
99"M_H_CPU1_SB_DQ<9>";
100"M_H_CPU1_SB_DQ<10>";
101"M_H_CPU1_SB_DQ<11>";
102"M_H_CPU1_SB_DQ<12>";
103"M_H_CPU1_SB_DQ<14>";
104"M_H_CPU1_SB_DQ<15>";
105"M_H_CPU1_SB_DQ<16>";
106"M_H_CPU1_SB_DQ<17>";
107"M_H_CPU1_SB_DQ<18>";
108"M_H_CPU1_SB_DQ<19>";
109"M_H_CPU1_SB_DQ<20>";
110"M_H_CPU1_SB_DQ<24>";
111"M_H_CPU1_SB_DQ<25>";
112"M_H_CPU1_SB_DQ<26>";
113"M_H_CPU1_SB_DQ<28>";
114"M_H_CPU1_SB_DQ<29>";
115"M_H_CPU1_SB_DQ<30>";
116"M_H_CPU1_SB_DQ<31>";
117"M_H_CPU1_SA_DQ<0>";
118"M_H_CPU1_SA_DQ<1>";
119"M_H_CPU1_SA_DQ<2>";
120"M_H_CPU1_SA_DQ<3>";
121"M_H_CPU1_SA_DQ<4>";
122"M_H_CPU1_SA_DQ<5>";
123"M_H_CPU1_SA_DQ<6>";
124"M_H_CPU1_SA_DQ<7>";
125"M_H_CPU1_SA_DQ<8>";
126"M_H_CPU1_SA_DQ<9>";
127"M_H_CPU1_SA_DQ<10>";
128"M_H_CPU1_SA_DQ<11>";
129"M_H_CPU1_SA_DQ<12>";
130"M_H_CPU1_SA_DQ<13>";
131"M_H_CPU1_SA_DQ<14>";
132"M_H_CPU1_SA_DQ<15>";
133"M_H_CPU1_SA_DQ<16>";
134"M_H_CPU1_SA_DQ<17>";
135"M_H_CPU1_SA_DQ<18>";
136"M_H_CPU1_SA_DQ<19>";
137"M_H_CPU1_SA_DQ<20>";
138"M_H_CPU1_SA_DQ<21>";
139"M_H_CPU1_SA_DQ<22>";
140"M_H_CPU1_SA_DQ<23>";
141"M_H_CPU1_SA_DQ<24>";
142"M_H_CPU1_SA_DQ<25>";
143"M_H_CPU1_SA_DQ<26>";
144"M_H_CPU1_SA_DQ<27>";
145"M_H_CPU1_SA_DQ<28>";
146"M_H_CPU1_SA_DQ<29>";
147"M_H_CPU1_SA_DQ<30>";
148"M_H_CPU1_SA_CS_N<1>";
149"M_H_CPU1_SA_CS_N<0>";
150"M_H_CPU1_CLK_DP<0>";
151"M_H_CPU1_CLK_DN<0>";
152"M_H_CPU1_SB_CB<0>";
153"M_H_CPU1_SB_CB<2>";
154"M_H_CPU1_SB_CB<3>";
155"M_H_CPU1_SB_CB<5>";
156"M_H_CPU1_SB_CB<6>";
157"M_H_CPU1_SA_CB<2>";
158"M_H_CPU1_SA_CB<3>";
159"M_H_CPU1_SA_CB<5>";
160"M_H_CPU1_SA_CB<6>";
161"M_H_CPU1_SB_CA<6>";
162"M_H_CPU1_SA_CA<6>";
163"M_H_CPU1_SB_CA<5>";
164"M_H_CPU1_SA_CA<5>";
165"M_H_CPU1_SA_CA<4>";
166"M_H_CPU1_SB_CA<3>";
167"M_H_CPU1_SA_CA<3>";
168"M_H_CPU1_SB_CA<2>";
169"M_H_CPU1_SA_CA<2>";
170"M_H_CPU1_SB_CA<1>";
171"M_H_CPU1_SA_CA<1>";
172"M_H_CPU1_SB_CA<0>";
173"M_H_CPU1_SB_CB<7>";
174"M_H_CPU1_SA_CB<1>";
175"M_H_CPU1_SA_CB<4>";
176"M_H_CPU1_SA_CB<7>";
177"M_H_CPU1_SA_DQ<31>";
178"PD_CHH_CPU1_DIMM1_SAA";
%"TAP"
"1","(-1600,3350)","0","standard","I100";
;
CDS_LIB"standard"
BODY_TYPE"PLUMBING"
HDL_TAP"TRUE";
"B \NAC \NWC"10;
"S \NAC"
BN"12"129;
%"TAP"
"1","(-1600,3450)","0","standard","I102";
;
CDS_LIB"standard"
BODY_TYPE"PLUMBING"
HDL_TAP"TRUE";
"B \NAC \NWC"10;
"S \NAC"
BN"14"131;
%"TAP"
"1","(-1600,3400)","0","standard","I103";
;
CDS_LIB"standard"
BODY_TYPE"PLUMBING"
HDL_TAP"TRUE";
"B \NAC \NWC"10;
"S \NAC"
BN"13"130;
%"TAP"
"1","(-1600,3500)","0","standard","I104";
;
CDS_LIB"standard"
BODY_TYPE"PLUMBING"
HDL_TAP"TRUE";
"B \NAC \NWC"10;
"S \NAC"
BN"15"132;
%"TAP"
"1","(-1600,3550)","0","standard","I105";
;
CDS_LIB"standard"
BODY_TYPE"PLUMBING"
HDL_TAP"TRUE";
"B \NAC \NWC"10;
"S \NAC"
BN"16"133;
%"TAP"
"1","(-1600,3600)","0","standard","I106";
;
CDS_LIB"standard"
BODY_TYPE"PLUMBING"
HDL_TAP"TRUE";
"B \NAC \NWC"10;
"S \NAC"
BN"17"134;
%"TAP"
"1","(-1600,3650)","0","standard","I107";
;
CDS_LIB"standard"
BODY_TYPE"PLUMBING"
HDL_TAP"TRUE";
"B \NAC \NWC"10;
"S \NAC"
BN"18"135;
%"TAP"
"1","(-1600,3700)","0","standard","I108";
;
CDS_LIB"standard"
BODY_TYPE"PLUMBING"
HDL_TAP"TRUE";
"B \NAC \NWC"10;
"S \NAC"
BN"19"136;
%"TAP"
"1","(-1600,3750)","0","standard","I109";
;
CDS_LIB"standard"
BODY_TYPE"PLUMBING"
HDL_TAP"TRUE";
"B \NAC \NWC"10;
"S \NAC"
BN"20"137;
%"TAP"
"1","(-1600,3800)","0","standard","I110";
;
CDS_LIB"standard"
BODY_TYPE"PLUMBING"
HDL_TAP"TRUE";
"B \NAC \NWC"10;
"S \NAC"
BN"21"138;
%"TAP"
"1","(-1600,3850)","0","standard","I111";
;
CDS_LIB"standard"
BODY_TYPE"PLUMBING"
HDL_TAP"TRUE";
"B \NAC \NWC"10;
"S \NAC"
BN"22"139;
%"TAP"
"1","(-1600,3900)","0","standard","I112";
;
CDS_LIB"standard"
BODY_TYPE"PLUMBING"
HDL_TAP"TRUE";
"B \NAC \NWC"10;
"S \NAC"
BN"23"140;
%"TAP"
"1","(-1600,3950)","0","standard","I113";
;
CDS_LIB"standard"
BODY_TYPE"PLUMBING"
HDL_TAP"TRUE";
"B \NAC \NWC"10;
"S \NAC"
BN"24"141;
%"TAP"
"1","(-1600,4000)","0","standard","I114";
;
CDS_LIB"standard"
BODY_TYPE"PLUMBING"
HDL_TAP"TRUE";
"B \NAC \NWC"10;
"S \NAC"
BN"25"142;
%"TAP"
"1","(-1600,4100)","0","standard","I115";
;
CDS_LIB"standard"
BODY_TYPE"PLUMBING"
HDL_TAP"TRUE";
"B \NAC \NWC"10;
"S \NAC"
BN"27"144;
%"TAP"
"1","(-1600,4050)","0","standard","I116";
;
CDS_LIB"standard"
BODY_TYPE"PLUMBING"
HDL_TAP"TRUE";
"B \NAC \NWC"10;
"S \NAC"
BN"26"143;
%"TAP"
"1","(-1600,4150)","0","standard","I117";
;
CDS_LIB"standard"
BODY_TYPE"PLUMBING"
HDL_TAP"TRUE";
"B \NAC \NWC"10;
"S \NAC"
BN"28"145;
%"TAP"
"1","(-1600,4300)","0","standard","I118";
;
CDS_LIB"standard"
BODY_TYPE"PLUMBING"
HDL_TAP"TRUE";
"B \NAC \NWC"10;
"S \NAC"
BN"31"177;
%"TAP"
"1","(-1600,4200)","0","standard","I119";
;
CDS_LIB"standard"
BODY_TYPE"PLUMBING"
HDL_TAP"TRUE";
"B \NAC \NWC"10;
"S \NAC"
BN"29"146;
%"VCC_CORE"
"1","(-4075,2175)","0","logical_power","I12";
;
HDL_POWER"P3V3_AUX"
CDS_LIB"logical_power";
"A"3;
%"TAP"
"1","(-1600,4250)","0","standard","I120";
;
CDS_LIB"standard"
BODY_TYPE"PLUMBING"
HDL_TAP"TRUE";
"B \NAC \NWC"10;
"S \NAC"
BN"30"147;
%"UNIVERSAL_GND"
"1","(125,50)","0","logical_power","I122";
;
HDL_POWER"GND"
CDS_LIB"logical_power";
"A"5;
%"UNIVERSAL_GND"
"1","(1750,50)","0","logical_power","I123";
;
HDL_POWER"GND"
CDS_LIB"logical_power";
"A"6;
%"Q_CAP"
"1","(125,425)","0","pure_quanta","I124";
;
PART_NUMBER"CH5221MEB00"
VOLTAGE"6.3V"
TOLERANCE"20%"
VALUE"2.2UF"
MATERIAL"X6S"
PACK_TYPE"C0402"
$LOCATION"C75"
CDS_LIB"pure_quanta"
$LOCATION"C75"
CDS_LOCATION"C75"
$SEC"1"
CDS_SEC"1";
"B"
$PN"2"5;
"A"
$PN"1"1;
%"Q_CAP"
"1","(1125,425)","0","pure_quanta","I125";
;
PART_NUMBER"CH6103KEA00"
VOLTAGE"16V"
PACK_TYPE"C0805"
TOLERANCE"10%"
VALUE"10UF"
MATERIAL"X6S"
$LOCATION"C76"
CDS_LIB"pure_quanta"
$LOCATION"C76"
CDS_LOCATION"C76"
$SEC"1"
CDS_SEC"1";
"B"
$PN"2"6;
"A"
$PN"1"4;
%"Q_CAP"
"1","(1750,425)","0","pure_quanta","I126";
;
PART_NUMBER"CH6103KEA00"
VOLTAGE"16V"
TOLERANCE"10%"
VALUE"10UF"
PACK_TYPE"C0805"
MATERIAL"X6S"
$LOCATION"C77"
CDS_LIB"pure_quanta"
$LOCATION"C77"
CDS_LOCATION"C77"
$SEC"1"
CDS_SEC"1";
"B"
$PN"2"6;
"A"
$PN"1"4;
%"VCC_CORE"
"1","(125,750)","0","logical_power","I127";
;
HDL_POWER"P3V3_AUX"
CDS_LIB"logical_power";
"A"1;
%"VCC_CORE"
"1","(1125,750)","0","logical_power","I129";
;
HDL_POWER"P12V_S3_AUX_CPU1_NVDIMM"
CDS_LIB"logical_power";
"A"4;
%"TAP"
"1","(1325,2300)","0","standard","I130";
;
CDS_LIB"standard"
BODY_TYPE"PLUMBING"
HDL_TAP"TRUE";
"B \NAC \NWC"18;
"S \NAC"
BN"0"54;
%"TAP"
"1","(1150,2350)","0","standard","I131";
;
CDS_LIB"standard"
BODY_TYPE"PLUMBING"
HDL_TAP"TRUE";
"B \NAC \NWC"16;
"S \NAC"
BN"0"74;
%"TAP"
"1","(1150,2450)","0","standard","I132";
;
CDS_LIB"standard"
BODY_TYPE"PLUMBING"
HDL_TAP"TRUE";
"B \NAC \NWC"16;
"S \NAC"
BN"1"73;
%"TAP"
"1","(1150,2550)","0","standard","I133";
;
CDS_LIB"standard"
BODY_TYPE"PLUMBING"
HDL_TAP"TRUE";
"B \NAC \NWC"16;
"S \NAC"
BN"2"72;
%"TAP"
"1","(1325,2500)","0","standard","I134";
;
CDS_LIB"standard"
BODY_TYPE"PLUMBING"
HDL_TAP"TRUE";
"B \NAC \NWC"18;
"S \NAC"
BN"2"52;
%"TAP"
"1","(1325,2400)","0","standard","I135";
;
CDS_LIB"standard"
BODY_TYPE"PLUMBING"
HDL_TAP"TRUE";
"B \NAC \NWC"18;
"S \NAC"
BN"1"53;
%"TAP"
"1","(1325,2600)","0","standard","I136";
;
CDS_LIB"standard"
BODY_TYPE"PLUMBING"
HDL_TAP"TRUE";
"B \NAC \NWC"18;
"S \NAC"
BN"3"51;
%"TAP"
"1","(1150,2650)","0","standard","I137";
;
CDS_LIB"standard"
BODY_TYPE"PLUMBING"
HDL_TAP"TRUE";
"B \NAC \NWC"16;
"S \NAC"
BN"3"71;
%"TAP"
"1","(1150,2750)","0","standard","I138";
;
CDS_LIB"standard"
BODY_TYPE"PLUMBING"
HDL_TAP"TRUE";
"B \NAC \NWC"16;
"S \NAC"
BN"4"70;
%"TAP"
"1","(1150,2850)","0","standard","I139";
;
CDS_LIB"standard"
BODY_TYPE"PLUMBING"
HDL_TAP"TRUE";
"B \NAC \NWC"16;
"S \NAC"
BN"5"69;
%"TAP"
"1","(-3250,2100)","2","standard","I14";
;
CDS_LIB"standard"
BODY_TYPE"PLUMBING"
HDL_TAP"TRUE";
"B \NAC \NWC"12;
"S \NAC"
BN"0"152;
%"TAP"
"1","(1325,2700)","0","standard","I140";
;
CDS_LIB"standard"
BODY_TYPE"PLUMBING"
HDL_TAP"TRUE";
"B \NAC \NWC"18;
"S \NAC"
BN"4"49;
%"TAP"
"1","(1325,2800)","0","standard","I141";
;
CDS_LIB"standard"
BODY_TYPE"PLUMBING"
HDL_TAP"TRUE";
"B \NAC \NWC"18;
"S \NAC"
BN"5"50;
%"TAP"
"1","(1150,2950)","0","standard","I142";
;
CDS_LIB"standard"
BODY_TYPE"PLUMBING"
HDL_TAP"TRUE";
"B \NAC \NWC"16;
"S \NAC"
BN"6"68;
%"TAP"
"1","(1150,3050)","0","standard","I143";
;
CDS_LIB"standard"
BODY_TYPE"PLUMBING"
HDL_TAP"TRUE";
"B \NAC \NWC"16;
"S \NAC"
BN"7"67;
%"TAP"
"1","(1325,3000)","0","standard","I144";
;
CDS_LIB"standard"
BODY_TYPE"PLUMBING"
HDL_TAP"TRUE";
"B \NAC \NWC"18;
"S \NAC"
BN"7"47;
%"TAP"
"1","(1325,2900)","0","standard","I145";
;
CDS_LIB"standard"
BODY_TYPE"PLUMBING"
HDL_TAP"TRUE";
"B \NAC \NWC"18;
"S \NAC"
BN"6"48;
%"TAP"
"1","(1325,3100)","0","standard","I146";
;
CDS_LIB"standard"
BODY_TYPE"PLUMBING"
HDL_TAP"TRUE";
"B \NAC \NWC"18;
"S \NAC"
BN"8"46;
%"TAP"
"1","(1150,3150)","0","standard","I147";
;
CDS_LIB"standard"
BODY_TYPE"PLUMBING"
HDL_TAP"TRUE";
"B \NAC \NWC"16;
"S \NAC"
BN"8"66;
%"TAP"
"1","(1150,3250)","0","standard","I148";
;
CDS_LIB"standard"
BODY_TYPE"PLUMBING"
HDL_TAP"TRUE";
"B \NAC \NWC"16;
"S \NAC"
BN"9"65;
%"TAP"
"1","(1325,3350)","0","standard","I149";
;
CDS_LIB"standard"
BODY_TYPE"PLUMBING"
HDL_TAP"TRUE";
"B \NAC \NWC"19;
"S \NAC"
BN"0"44;
%"TAP"
"1","(-3250,2150)","2","standard","I15";
;
CDS_LIB"standard"
BODY_TYPE"PLUMBING"
HDL_TAP"TRUE";
"B \NAC \NWC"12;
"S \NAC"
BN"1"34;
%"TAP"
"1","(1325,3200)","0","standard","I150";
;
CDS_LIB"standard"
BODY_TYPE"PLUMBING"
HDL_TAP"TRUE";
"B \NAC \NWC"18;
"S \NAC"
BN"9"45;
%"TAP"
"1","(1150,3500)","0","standard","I151";
;
CDS_LIB"standard"
BODY_TYPE"PLUMBING"
HDL_TAP"TRUE";
"B \NAC \NWC"17;
"S \NAC"
BN"1"63;
%"TAP"
"1","(1150,3400)","0","standard","I152";
;
CDS_LIB"standard"
BODY_TYPE"PLUMBING"
HDL_TAP"TRUE";
"B \NAC \NWC"17;
"S \NAC"
BN"0"64;
%"TAP"
"1","(1150,3600)","0","standard","I153";
;
CDS_LIB"standard"
BODY_TYPE"PLUMBING"
HDL_TAP"TRUE";
"B \NAC \NWC"17;
"S \NAC"
BN"2"62;
%"TAP"
"1","(1325,3450)","0","standard","I154";
;
CDS_LIB"standard"
BODY_TYPE"PLUMBING"
HDL_TAP"TRUE";
"B \NAC \NWC"19;
"S \NAC"
BN"1"43;
%"TAP"
"1","(1325,3650)","0","standard","I155";
;
CDS_LIB"standard"
BODY_TYPE"PLUMBING"
HDL_TAP"TRUE";
"B \NAC \NWC"19;
"S \NAC"
BN"3"41;
%"TAP"
"1","(1325,3550)","0","standard","I156";
;
CDS_LIB"standard"
BODY_TYPE"PLUMBING"
HDL_TAP"TRUE";
"B \NAC \NWC"19;
"S \NAC"
BN"2"42;
%"TAP"
"1","(1150,3700)","0","standard","I157";
;
CDS_LIB"standard"
BODY_TYPE"PLUMBING"
HDL_TAP"TRUE";
"B \NAC \NWC"17;
"S \NAC"
BN"3"61;
%"TAP"
"1","(1150,3800)","0","standard","I158";
;
CDS_LIB"standard"
BODY_TYPE"PLUMBING"
HDL_TAP"TRUE";
"B \NAC \NWC"17;
"S \NAC"
BN"4"60;
%"TAP"
"1","(1150,3900)","0","standard","I159";
;
CDS_LIB"standard"
BODY_TYPE"PLUMBING"
HDL_TAP"TRUE";
"B \NAC \NWC"17;
"S \NAC"
BN"5"59;
%"TAP"
"1","(-3250,2200)","2","standard","I16";
;
CDS_LIB"standard"
BODY_TYPE"PLUMBING"
HDL_TAP"TRUE";
"B \NAC \NWC"12;
"S \NAC"
BN"2"153;
%"TAP"
"1","(1325,3750)","0","standard","I160";
;
CDS_LIB"standard"
BODY_TYPE"PLUMBING"
HDL_TAP"TRUE";
"B \NAC \NWC"19;
"S \NAC"
BN"4"40;
%"TAP"
"1","(1325,3850)","0","standard","I161";
;
CDS_LIB"standard"
BODY_TYPE"PLUMBING"
HDL_TAP"TRUE";
"B \NAC \NWC"19;
"S \NAC"
BN"5"39;
%"TAP"
"1","(1150,4000)","0","standard","I162";
;
CDS_LIB"standard"
BODY_TYPE"PLUMBING"
HDL_TAP"TRUE";
"B \NAC \NWC"17;
"S \NAC"
BN"6"58;
%"TAP"
"1","(1150,4100)","0","standard","I163";
;
CDS_LIB"standard"
BODY_TYPE"PLUMBING"
HDL_TAP"TRUE";
"B \NAC \NWC"17;
"S \NAC"
BN"7"57;
%"TAP"
"1","(1325,3950)","0","standard","I164";
;
CDS_LIB"standard"
BODY_TYPE"PLUMBING"
HDL_TAP"TRUE";
"B \NAC \NWC"19;
"S \NAC"
BN"6"38;
%"TAP"
"1","(1325,4150)","0","standard","I165";
;
CDS_LIB"standard"
BODY_TYPE"PLUMBING"
HDL_TAP"TRUE";
"B \NAC \NWC"19;
"S \NAC"
BN"8"36;
%"TAP"
"1","(1325,4050)","0","standard","I166";
;
CDS_LIB"standard"
BODY_TYPE"PLUMBING"
HDL_TAP"TRUE";
"B \NAC \NWC"19;
"S \NAC"
BN"7"37;
%"TAP"
"1","(1150,4200)","0","standard","I167";
;
CDS_LIB"standard"
BODY_TYPE"PLUMBING"
HDL_TAP"TRUE";
"B \NAC \NWC"17;
"S \NAC"
BN"8"56;
%"TAP"
"1","(1150,4300)","0","standard","I168";
;
CDS_LIB"standard"
BODY_TYPE"PLUMBING"
HDL_TAP"TRUE";
"B \NAC \NWC"17;
"S \NAC"
BN"9"55;
%"TAP"
"1","(1325,4250)","0","standard","I169";
;
CDS_LIB"standard"
BODY_TYPE"PLUMBING"
HDL_TAP"TRUE";
"B \NAC \NWC"19;
"S \NAC"
BN"9"35;
%"TAP"
"1","(-3250,2250)","2","standard","I17";
;
CDS_LIB"standard"
BODY_TYPE"PLUMBING"
HDL_TAP"TRUE";
"B \NAC \NWC"12;
"S \NAC"
BN"3"154;
%"UNIVERSAL_GND"
"1","(2825,600)","0","logical_power","I170";
;
HDL_POWER"GND"
CDS_LIB"logical_power";
"A"7;
%"VCC_CORE"
"1","(2825,4850)","0","logical_power","I176";
;
HDL_POWER"P12V_S3_AUX_CPU1_NVDIMM"
CDS_LIB"logical_power";
"A"2;
%"UNIVERSAL_GND"
"1","(4525,600)","0","logical_power","I177";
;
HDL_POWER"GND"
CDS_LIB"logical_power";
"A"8;
%"SCONN288_ADR50017P130CC"
"3","(3675,2675)","0","pure_quanta","I178";
;
PART_NUMBER"DFHST8FS461"
MATERIAL"IO"
VALUE"SCONN288_ADR50017-P130CC"
PART_TYPE"SMLF"
$LOCATION"J31"
NEEDS_NO_SIZE"TRUE"
CDS_LMAN_SYM_OUTLINE"-450,1775,450,-1775"
CDS_LIB"pure_quanta"
CDS_LOCATION"J31"
$SEC"3"
CDS_SEC"3";
"G3"
$PN"G3"8;
"G2"
$PN"G2"8;
"G1"
$PN"G1"8;
"VSS62"
$PN"141"8;
"VSS61"
$PN"139"8;
"VSS60"
$PN"136"8;
"VSS58"
$PN"132"8;
"VSS104"
$PN"240"7;
"VSS102"
$PN"235"7;
"VSS100"
$PN"230"7;
"VIN_BULK2"
$PN"146"2;
"VIN_BULK1"
$PN"145"2;
"VIN_BULK0"
$PN"1"2;
"VSS126"
$PN"288"7;
"VSS125"
$PN"286"7;
"VSS124"
$PN"284"7;
"VSS123"
$PN"281"7;
"VSS122"
$PN"279"7;
"VSS121"
$PN"277"7;
"VSS120"
$PN"275"7;
"VSS119"
$PN"273"7;
"VSS118"
$PN"270"7;
"VSS117"
$PN"268"7;
"VSS116"
$PN"266"7;
"VSS115"
$PN"264"7;
"VSS114"
$PN"262"7;
"VSS113"
$PN"259"7;
"VSS112"
$PN"257"7;
"VSS111"
$PN"255"7;
"VSS110"
$PN"253"7;
"VSS109"
$PN"251"7;
"VSS108"
$PN"248"7;
"VSS107"
$PN"246"7;
"VSS106"
$PN"244"7;
"VSS105"
$PN"242"7;
"VSS103"
$PN"237"7;
"VSS101"
$PN"233"7;
"VSS99"
$PN"228"7;
"VSS98"
$PN"226"7;
"VSS97"
$PN"224"7;
"VSS96"
$PN"222"7;
"VSS95"
$PN"219"7;
"VSS94"
$PN"216"7;
"VSS93"
$PN"214"7;
"VSS92"
$PN"212"7;
"VSS91"
$PN"210"7;
"VSS90"
$PN"208"7;
"VSS89"
$PN"206"7;
"VSS88"
$PN"204"7;
"VSS87"
$PN"202"7;
"VSS86"
$PN"199"7;
"VSS85"
$PN"197"7;
"VSS84"
$PN"195"7;
"VSS83"
$PN"193"7;
"VSS82"
$PN"191"7;
"VSS81"
$PN"188"7;
"VSS80"
$PN"186"7;
"VSS79"
$PN"184"7;
"VSS78"
$PN"182"7;
"VSS77"
$PN"180"7;
"VSS76"
$PN"177"7;
"VSS75"
$PN"175"7;
"VSS74"
$PN"173"7;
"VSS73"
$PN"171"7;
"VSS72"
$PN"169"7;
"VSS71"
$PN"166"7;
"VSS70"
$PN"164"7;
"VSS69"
$PN"162"7;
"VSS68"
$PN"160"7;
"VSS67"
$PN"158"7;
"VSS66"
$PN"155"7;
"VSS65"
$PN"153"7;
"VSS64"
$PN"151"7;
"VSS63"
$PN"143"8;
"VSS59"
$PN"134"8;
"VSS57"
$PN"130"8;
"VSS56"
$PN"128"8;
"VSS55"
$PN"125"8;
"VSS54"
$PN"123"8;
"VSS53"
$PN"121"8;
"VSS52"
$PN"119"8;
"VSS51"
$PN"117"8;
"VSS50"
$PN"114"8;
"VSS49"
$PN"112"8;
"VSS48"
$PN"110"8;
"VSS47"
$PN"108"8;
"VSS46"
$PN"106"8;
"VSS45"
$PN"103"8;
"VSS44"
$PN"101"8;
"VSS43"
$PN"99"8;
"VSS42"
$PN"97"8;
"VSS41"
$PN"95"8;
"VSS40"
$PN"92"8;
"VSS39"
$PN"90"8;
"VSS38"
$PN"88"8;
"VSS37"
$PN"85"8;
"VSS36"
$PN"83"8;
"VSS35"
$PN"81"8;
"VSS34"
$PN"79"8;
"VSS33"
$PN"77"8;
"VSS32"
$PN"75"8;
"VSS31"
$PN"73"8;
"VSS30"
$PN"71"8;
"VSS29"
$PN"69"8;
"VSS28"
$PN"67"8;
"VSS27"
$PN"65"8;
"VSS26"
$PN"63"8;
"VSS25"
$PN"61"8;
"VSS24"
$PN"59"8;
"VSS23"
$PN"57"8;
"VSS22"
$PN"54"8;
"VSS21"
$PN"52"8;
"VSS20"
$PN"50"8;
"VSS19"
$PN"48"8;
"VSS18"
$PN"46"8;
"VSS17"
$PN"43"8;
"VSS16"
$PN"41"8;
"VSS15"
$PN"39"8;
"VSS14"
$PN"37"8;
"VSS13"
$PN"35"8;
"VSS12"
$PN"32"8;
"VSS11"
$PN"30"8;
"VSS10"
$PN"28"8;
"VSS9"
$PN"26"8;
"VSS8"
$PN"24"8;
"VSS7"
$PN"21"8;
"VSS6"
$PN"19"8;
"VSS5"
$PN"17"8;
"VSS4"
$PN"15"8;
"VSS3"
$PN"13"8;
"VSS2"
$PN"10"8;
"VSS1"
$PN"8"8;
"VSS0"
$PN"6"8;
%"TAP"
"1","(-3250,2300)","2","standard","I18";
;
CDS_LIB"standard"
BODY_TYPE"PLUMBING"
HDL_TAP"TRUE";
"B \NAC \NWC"12;
"S \NAC"
BN"4"83;
%"SCONN288_ADR50017P130CC"
"1","(-2425,2575)","0","pure_quanta","I180";
;
PART_NUMBER"DFHST8FS461"
MATERIAL"IO"
PART_TYPE"SMLF"
VALUE"SCONN288_ADR50017-P130CC"
$LOCATION"J31"
NEEDS_NO_SIZE"TRUE"
CDS_LMAN_SYM_OUTLINE"-450,1875,450,-1875"
CDS_LIB"pure_quanta"
CDS_LOCATION"J31"
$SEC"1"
CDS_SEC"1";
"DQ31_A"
$PN"194"177;
"CB7_A"
$PN"205"176;
"CB4_A"
$PN"58"175;
"CB1_A"
$PN"53"174;
"CB7_B"
$PN"236"173;
"ALERT_N \B"
$PN"62"30;
"CA0_A"
$PN"66"76;
"CA0_B"
$PN"76"172;
"CA1_A"
$PN"211"171;
"CA1_B"
$PN"221"170;
"CA2_A"
$PN"68"169;
"CA2_B"
$PN"78"168;
"CA3_A"
$PN"213"167;
"CA3_B"
$PN"223"166;
"CA4_A"
$PN"70"165;
"CA4_B"
$PN"80"77;
"CA5_A"
$PN"215"164;
"CA5_B"
$PN"225"163;
"CA6_A"
$PN"72"162;
"CA6_B"
$PN"82"161;
"CB6_A"
$PN"203"160;
"CB5_A"
$PN"60"159;
"CB3_A"
$PN"198"158;
"CB2_A"
$PN"196"157;
"CB0_A"
$PN"51"75;
"CB6_B"
$PN"234"156;
"CB5_B"
$PN"91"155;
"CB4_B"
$PN"89"83;
"CB3_B"
$PN"243"154;
"CB2_B"
$PN"241"153;
"CB1_B"
$PN"98"34;
"CB0_B"
$PN"96"152;
"CK_C \B"
$PN"218"151;
"CK_T"
$PN"217"150;
"CS0_A_N"
$PN"64"149;
"CS0_B_N"
$PN"84"79;
"CS1_A_N"
$PN"209"148;
"CS1_B_N"
$PN"229"78;
"DQ30_A"
$PN"192"147;
"DQ29_A"
$PN"49"146;
"DQ28_A"
$PN"47"145;
"DQ27_A"
$PN"187"144;
"DQ26_A"
$PN"185"143;
"DQ25_A"
$PN"42"142;
"DQ24_A"
$PN"40"141;
"DQ23_A"
$PN"183"140;
"DQ22_A"
$PN"181"139;
"DQ21_A"
$PN"38"138;
"DQ20_A"
$PN"36"137;
"DQ19_A"
$PN"176"136;
"DQ18_A"
$PN"174"135;
"DQ17_A"
$PN"31"134;
"DQ16_A"
$PN"29"133;
"DQ15_A"
$PN"172"132;
"DQ14_A"
$PN"170"131;
"DQ13_A"
$PN"27"130;
"DQ12_A"
$PN"25"129;
"DQ11_A"
$PN"165"128;
"DQ10_A"
$PN"163"127;
"DQ9_A"
$PN"20"126;
"DQ8_A"
$PN"18"125;
"DQ7_A"
$PN"161"124;
"DQ6_A"
$PN"159"123;
"DQ5_A"
$PN"16"122;
"DQ4_A"
$PN"14"121;
"DQ3_A"
$PN"154"120;
"DQ2_A"
$PN"152"119;
"DQ1_A"
$PN"9"118;
"DQ0_A"
$PN"7"117;
"DQ31_B"
$PN"287"116;
"DQ30_B"
$PN"285"115;
"DQ29_B"
$PN"142"114;
"DQ28_B"
$PN"140"113;
"DQ27_B"
$PN"280"84;
"DQ26_B"
$PN"278"112;
"DQ25_B"
$PN"135"111;
"DQ24_B"
$PN"133"110;
"DQ23_B"
$PN"276"80;
"DQ22_B"
$PN"274"81;
"DQ21_B"
$PN"131"82;
"DQ20_B"
$PN"129"109;
"DQ19_B"
$PN"269"108;
"DQ18_B"
$PN"267"107;
"DQ17_B"
$PN"124"106;
"DQ16_B"
$PN"122"105;
"DQ15_B"
$PN"265"104;
"DQ14_B"
$PN"263"103;
"DQ13_B"
$PN"120"85;
"DQ12_B"
$PN"118"102;
"DQ11_B"
$PN"258"101;
"DQ10_B"
$PN"256"100;
"DQ9_B"
$PN"113"99;
"DQ8_B"
$PN"111"98;
"DQ7_B"
$PN"254"97;
"DQ6_B"
$PN"252"96;
"DQ5_B"
$PN"109"95;
"DQ4_B"
$PN"107"94;
"DQ3_B"
$PN"247"93;
"DQ2_B"
$PN"245"20;
"DQ1_B"
$PN"102"92;
"DQ0_B"
$PN"100"91;
"HSA"
$PN"148"32;
"HSCL"
$PN"4"29;
"HSDA"
$PN"5"33;
"LBD||RSP_A_N"
$PN"86"90;
"LBS||RSP_B_N"
$PN"87"89;
"PAR_A"
$PN"74"88;
"PAR_B"
$PN"227"87;
"PWR_GOOD||FAIL_N"
$PN"147"21;
"RESET_N \B"
$PN"207"31;
"RFU6"
$PN"232"22;
"RFU5"
$PN"231"86;
"RFU4"
$PN"220"23;
"RFU3"
$PN"150"24;
"RFU2"
$PN"149"25;
"RFU1"
$PN"144"26;
"RFU0"
$PN"2"27;
"VIN_MGMT"
$PN"3"3;
%"SCONN288_ADR50017P130CC"
"2","(250,3300)","0","pure_quanta","I181";
;
PART_NUMBER"DFHST8FS461"
PART_TYPE"SMLF"
VALUE"SCONN288_ADR50017-P130CC"
MATERIAL"IO"
LOCATION"J31"
NEEDS_NO_SIZE"TRUE"
CDS_LMAN_SYM_OUTLINE"-600,1150,600,-1150"
CDS_LIB"pure_quanta"
$SEC"2"
CDS_SEC"2";
"DQS7_A_C||TDQS7_A_C \B"
$PN"178"37;
"DQS6_A_T||TDQS6_A_T"
$PN"168"58;
"DQS8_B_T||TDQS8_B_T"
$PN"283"66;
"DQS8_B_C||TDQS8_B_C \B"
$PN"282"46;
"DQS7_B_T||TDQS7_B_T"
$PN"272"67;
"DQS0_A_C \B"
$PN"12"44;
"DQS0_A_T"
$PN"11"64;
"DQS0_B_C \B"
$PN"105"54;
"DQS0_B_T"
$PN"104"74;
"DQS1_A_C \B"
$PN"23"43;
"DQS1_A_T"
$PN"22"63;
"DQS1_B_C \B"
$PN"116"53;
"DQS1_B_T"
$PN"115"73;
"DQS2_A_C \B"
$PN"34"42;
"DQS2_A_T"
$PN"33"62;
"DQS2_B_C \B"
$PN"127"52;
"DQS2_B_T"
$PN"126"72;
"DQS3_A_C \B"
$PN"45"41;
"DQS3_A_T"
$PN"44"61;
"DQS3_B_C \B"
$PN"138"51;
"DQS3_B_T"
$PN"137"71;
"DQS4_A_C \B"
$PN"56"40;
"DQS4_A_T"
$PN"55"60;
"DQS4_B_C \B"
$PN"238"49;
"DQS4_B_T"
$PN"239"70;
"DQS5_A_C||TDQS5_A_C||DQS5_A_T||TDQS5_A_T \B"
$PN"156"39;
"DQS5_A_T||TDQS5_A_T"
$PN"157"59;
"DQS5_B_C||TDQS5_B_C \B"
$PN"249"50;
"DQS5_B_T||TDQS5_B_T"
$PN"250"69;
"DQS6_A_C||TDQS6_A_C||DQS6_A_T||TDQS6_A_T \B"
$PN"167"38;
"DQS6_B_C||TDQS6_B_C \B"
$PN"260"48;
"DQS6_B_T||TDQS6_B_T"
$PN"261"68;
"DQS7_A_T||TDQS7_A_T"
$PN"179"57;
"DQS7_B_C||TDQS7_B_C \B"
$PN"271"47;
"DQS8_A_C||TDQS8_A_C \B"
$PN"189"36;
"DQS8_A_T||TDQS8_A_T"
$PN"190"56;
"DQS9_A_C||TDQS9_A_C \B"
$PN"200"35;
"DQS9_A_T||TDQS9_A_T"
$PN"201"55;
"DQS9_B_C||TDQS9_B_C \B"
$PN"94"45;
"DQS9_B_T||TDQS9_B_T||DBI4_B_N"
$PN"93"65;
%"Q_RES"
"1","(-4200,1600)","0","pure_quanta","I183";
;
PART_NUMBER"CS04992FB07"
VALUE"49.9"
MATERIAL"CHIP"
$LOCATION"R3905"
CDS_LIB"pure_quanta"
PACK_TYPE"0402LF"
TOLERANCE"1%"
WATTAGE"1/16W"
CDS_LOCATION"R3905"
$SEC"1"
CDS_SEC"1";
"B"
$PN"2"28;
"A"
$PN"1"29;
%"TAP"
"1","(-3250,2350)","2","standard","I19";
;
CDS_LIB"standard"
BODY_TYPE"PLUMBING"
HDL_TAP"TRUE";
"B \NAC \NWC"12;
"S \NAC"
BN"5"155;
%"UNIVERSAL_GND"
"1","(-3025,-75)","0","logical_power","I2";
;
HDL_POWER"GND"
CDS_LIB"logical_power";
"A"9;
%"Q_RES"
"2","(-3025,150)","0","pure_quanta","I3";
;
PART_NUMBER"CS41272FB07"
VALUE"127K"
PACK_TYPE"0402LF"
TOLERANCE"1%"
WATTAGE"1/16W"
MATERIAL"CHIP"
$LOCATION"R73"
CDS_LIB"pure_quanta"
$LOCATION"R73"
CDS_LOCATION"R73"
$SEC"1"
CDS_SEC"1";
"A"
$PN"1"178;
"B"
$PN"2"9;
%"TAP"
"1","(-3250,2400)","2","standard","I32";
;
CDS_LIB"standard"
BODY_TYPE"PLUMBING"
HDL_TAP"TRUE";
"B \NAC \NWC"12;
"S \NAC"
BN"6"156;
%"TAP"
"1","(-3250,2450)","2","standard","I33";
;
CDS_LIB"standard"
BODY_TYPE"PLUMBING"
HDL_TAP"TRUE";
"B \NAC \NWC"12;
"S \NAC"
BN"7"173;
%"TAP"
"1","(-3250,2550)","2","standard","I34";
;
CDS_LIB"standard"
BODY_TYPE"PLUMBING"
HDL_TAP"TRUE";
"B \NAC \NWC"11;
"S \NAC"
BN"0"75;
%"TAP"
"1","(-3250,2600)","2","standard","I35";
;
CDS_LIB"standard"
BODY_TYPE"PLUMBING"
HDL_TAP"TRUE";
"B \NAC \NWC"11;
"S \NAC"
BN"1"174;
%"TAP"
"1","(-3250,2650)","2","standard","I36";
;
CDS_LIB"standard"
BODY_TYPE"PLUMBING"
HDL_TAP"TRUE";
"B \NAC \NWC"11;
"S \NAC"
BN"2"157;
%"TAP"
"1","(-3250,2700)","2","standard","I37";
;
CDS_LIB"standard"
BODY_TYPE"PLUMBING"
HDL_TAP"TRUE";
"B \NAC \NWC"11;
"S \NAC"
BN"3"158;
%"TAP"
"1","(-3250,2750)","2","standard","I38";
;
CDS_LIB"standard"
BODY_TYPE"PLUMBING"
HDL_TAP"TRUE";
"B \NAC \NWC"11;
"S \NAC"
BN"4"175;
%"TAP"
"1","(-3250,2800)","2","standard","I39";
;
CDS_LIB"standard"
BODY_TYPE"PLUMBING"
HDL_TAP"TRUE";
"B \NAC \NWC"11;
"S \NAC"
BN"5"159;
%"TAP"
"1","(-3250,2850)","2","standard","I40";
;
CDS_LIB"standard"
BODY_TYPE"PLUMBING"
HDL_TAP"TRUE";
"B \NAC \NWC"11;
"S \NAC"
BN"6"160;
%"TAP"
"1","(-3250,2900)","2","standard","I41";
;
CDS_LIB"standard"
BODY_TYPE"PLUMBING"
HDL_TAP"TRUE";
"B \NAC \NWC"11;
"S \NAC"
BN"7"176;
%"TAP"
"1","(-3250,3650)","2","standard","I42";
;
CDS_LIB"standard"
BODY_TYPE"PLUMBING"
HDL_TAP"TRUE";
"B \NAC \NWC"13;
"S \NAC"
BN"1"170;
%"TAP"
"1","(-3250,3600)","2","standard","I43";
;
CDS_LIB"standard"
BODY_TYPE"PLUMBING"
HDL_TAP"TRUE";
"B \NAC \NWC"13;
"S \NAC"
BN"0"172;
%"TAP"
"1","(-3250,3700)","2","standard","I44";
;
CDS_LIB"standard"
BODY_TYPE"PLUMBING"
HDL_TAP"TRUE";
"B \NAC \NWC"13;
"S \NAC"
BN"2"168;
%"TAP"
"1","(-3250,3750)","2","standard","I45";
;
CDS_LIB"standard"
BODY_TYPE"PLUMBING"
HDL_TAP"TRUE";
"B \NAC \NWC"13;
"S \NAC"
BN"3"166;
%"TAP"
"1","(-3250,3800)","2","standard","I46";
;
CDS_LIB"standard"
BODY_TYPE"PLUMBING"
HDL_TAP"TRUE";
"B \NAC \NWC"13;
"S \NAC"
BN"4"77;
%"TAP"
"1","(-3250,3900)","2","standard","I47";
;
CDS_LIB"standard"
BODY_TYPE"PLUMBING"
HDL_TAP"TRUE";
"B \NAC \NWC"13;
"S \NAC"
BN"6"161;
%"TAP"
"1","(-3250,3850)","2","standard","I48";
;
CDS_LIB"standard"
BODY_TYPE"PLUMBING"
HDL_TAP"TRUE";
"B \NAC \NWC"13;
"S \NAC"
BN"5"163;
%"TAP"
"1","(-3250,4000)","2","standard","I49";
;
CDS_LIB"standard"
BODY_TYPE"PLUMBING"
HDL_TAP"TRUE";
"B \NAC \NWC"14;
"S \NAC"
BN"0"76;
%"TAP"
"1","(-3250,4100)","2","standard","I50";
;
CDS_LIB"standard"
BODY_TYPE"PLUMBING"
HDL_TAP"TRUE";
"B \NAC \NWC"14;
"S \NAC"
BN"2"169;
%"TAP"
"1","(-3250,4050)","2","standard","I51";
;
CDS_LIB"standard"
BODY_TYPE"PLUMBING"
HDL_TAP"TRUE";
"B \NAC \NWC"14;
"S \NAC"
BN"1"171;
%"TAP"
"1","(-3250,4150)","2","standard","I52";
;
CDS_LIB"standard"
BODY_TYPE"PLUMBING"
HDL_TAP"TRUE";
"B \NAC \NWC"14;
"S \NAC"
BN"3"167;
%"TAP"
"1","(-3250,4200)","2","standard","I53";
;
CDS_LIB"standard"
BODY_TYPE"PLUMBING"
HDL_TAP"TRUE";
"B \NAC \NWC"14;
"S \NAC"
BN"4"165;
%"TAP"
"1","(-3250,4250)","2","standard","I54";
;
CDS_LIB"standard"
BODY_TYPE"PLUMBING"
HDL_TAP"TRUE";
"B \NAC \NWC"14;
"S \NAC"
BN"5"164;
%"TAP"
"1","(-3250,4300)","2","standard","I55";
;
CDS_LIB"standard"
BODY_TYPE"PLUMBING"
HDL_TAP"TRUE";
"B \NAC \NWC"14;
"S \NAC"
BN"6"162;
%"TAP"
"1","(-1600,1200)","0","standard","I56";
;
CDS_LIB"standard"
BODY_TYPE"PLUMBING"
HDL_TAP"TRUE";
"B \NAC \NWC"15;
"S \NAC"
BN"2"20;
%"TAP"
"1","(-1600,1100)","0","standard","I57";
;
CDS_LIB"standard"
BODY_TYPE"PLUMBING"
HDL_TAP"TRUE";
"B \NAC \NWC"15;
"S \NAC"
BN"0"91;
%"TAP"
"1","(-1600,1150)","0","standard","I58";
;
CDS_LIB"standard"
BODY_TYPE"PLUMBING"
HDL_TAP"TRUE";
"B \NAC \NWC"15;
"S \NAC"
BN"1"92;
%"TAP"
"1","(-1600,1250)","0","standard","I59";
;
CDS_LIB"standard"
BODY_TYPE"PLUMBING"
HDL_TAP"TRUE";
"B \NAC \NWC"15;
"S \NAC"
BN"3"93;
%"TAP"
"1","(-1600,1300)","0","standard","I60";
;
CDS_LIB"standard"
BODY_TYPE"PLUMBING"
HDL_TAP"TRUE";
"B \NAC \NWC"15;
"S \NAC"
BN"4"94;
%"TAP"
"1","(-1600,1400)","0","standard","I61";
;
CDS_LIB"standard"
BODY_TYPE"PLUMBING"
HDL_TAP"TRUE";
"B \NAC \NWC"15;
"S \NAC"
BN"6"96;
%"TAP"
"1","(-1600,1350)","0","standard","I62";
;
CDS_LIB"standard"
BODY_TYPE"PLUMBING"
HDL_TAP"TRUE";
"B \NAC \NWC"15;
"S \NAC"
BN"5"95;
%"TAP"
"1","(-1600,1450)","0","standard","I63";
;
CDS_LIB"standard"
BODY_TYPE"PLUMBING"
HDL_TAP"TRUE";
"B \NAC \NWC"15;
"S \NAC"
BN"7"97;
%"TAP"
"1","(-1600,1500)","0","standard","I64";
;
CDS_LIB"standard"
BODY_TYPE"PLUMBING"
HDL_TAP"TRUE";
"B \NAC \NWC"15;
"S \NAC"
BN"8"98;
%"TAP"
"1","(-1600,1550)","0","standard","I65";
;
CDS_LIB"standard"
BODY_TYPE"PLUMBING"
HDL_TAP"TRUE";
"B \NAC \NWC"15;
"S \NAC"
BN"9"99;
%"TAP"
"1","(-1600,1600)","0","standard","I66";
;
CDS_LIB"standard"
BODY_TYPE"PLUMBING"
HDL_TAP"TRUE";
"B \NAC \NWC"15;
"S \NAC"
BN"10"100;
%"TAP"
"1","(-1600,1650)","0","standard","I67";
;
CDS_LIB"standard"
BODY_TYPE"PLUMBING"
HDL_TAP"TRUE";
"B \NAC \NWC"15;
"S \NAC"
BN"11"101;
%"TAP"
"1","(-1600,1700)","0","standard","I68";
;
CDS_LIB"standard"
BODY_TYPE"PLUMBING"
HDL_TAP"TRUE";
"B \NAC \NWC"15;
"S \NAC"
BN"12"102;
%"TAP"
"1","(-1600,1750)","0","standard","I69";
;
CDS_LIB"standard"
BODY_TYPE"PLUMBING"
HDL_TAP"TRUE";
"B \NAC \NWC"15;
"S \NAC"
BN"13"85;
%"TAP"
"1","(-1600,1800)","0","standard","I70";
;
CDS_LIB"standard"
BODY_TYPE"PLUMBING"
HDL_TAP"TRUE";
"B \NAC \NWC"15;
"S \NAC"
BN"14"103;
%"TAP"
"1","(-1600,1850)","0","standard","I71";
;
CDS_LIB"standard"
BODY_TYPE"PLUMBING"
HDL_TAP"TRUE";
"B \NAC \NWC"15;
"S \NAC"
BN"15"104;
%"TAP"
"1","(-1600,1900)","0","standard","I72";
;
CDS_LIB"standard"
BODY_TYPE"PLUMBING"
HDL_TAP"TRUE";
"B \NAC \NWC"15;
"S \NAC"
BN"16"105;
%"TAP"
"1","(-1600,1950)","0","standard","I73";
;
CDS_LIB"standard"
BODY_TYPE"PLUMBING"
HDL_TAP"TRUE";
"B \NAC \NWC"15;
"S \NAC"
BN"17"106;
%"TAP"
"1","(-1600,2050)","0","standard","I74";
;
CDS_LIB"standard"
BODY_TYPE"PLUMBING"
HDL_TAP"TRUE";
"B \NAC \NWC"15;
"S \NAC"
BN"19"108;
%"TAP"
"1","(-1600,2000)","0","standard","I75";
;
CDS_LIB"standard"
BODY_TYPE"PLUMBING"
HDL_TAP"TRUE";
"B \NAC \NWC"15;
"S \NAC"
BN"18"107;
%"TAP"
"1","(-1600,2100)","0","standard","I76";
;
CDS_LIB"standard"
BODY_TYPE"PLUMBING"
HDL_TAP"TRUE";
"B \NAC \NWC"15;
"S \NAC"
BN"20"109;
%"TAP"
"1","(-1600,2200)","0","standard","I77";
;
CDS_LIB"standard"
BODY_TYPE"PLUMBING"
HDL_TAP"TRUE";
"B \NAC \NWC"15;
"S \NAC"
BN"22"81;
%"TAP"
"1","(-1600,2150)","0","standard","I78";
;
CDS_LIB"standard"
BODY_TYPE"PLUMBING"
HDL_TAP"TRUE";
"B \NAC \NWC"15;
"S \NAC"
BN"21"82;
%"TAP"
"1","(-1600,2250)","0","standard","I79";
;
CDS_LIB"standard"
BODY_TYPE"PLUMBING"
HDL_TAP"TRUE";
"B \NAC \NWC"15;
"S \NAC"
BN"23"80;
%"TAP"
"1","(-1600,2300)","0","standard","I80";
;
CDS_LIB"standard"
BODY_TYPE"PLUMBING"
HDL_TAP"TRUE";
"B \NAC \NWC"15;
"S \NAC"
BN"24"110;
%"TAP"
"1","(-1600,2350)","0","standard","I81";
;
CDS_LIB"standard"
BODY_TYPE"PLUMBING"
HDL_TAP"TRUE";
"B \NAC \NWC"15;
"S \NAC"
BN"25"111;
%"TAP"
"1","(-1600,2450)","0","standard","I82";
;
CDS_LIB"standard"
BODY_TYPE"PLUMBING"
HDL_TAP"TRUE";
"B \NAC \NWC"15;
"S \NAC"
BN"27"84;
%"TAP"
"1","(-1600,2400)","0","standard","I83";
;
CDS_LIB"standard"
BODY_TYPE"PLUMBING"
HDL_TAP"TRUE";
"B \NAC \NWC"15;
"S \NAC"
BN"26"112;
%"TAP"
"1","(-1600,2500)","0","standard","I84";
;
CDS_LIB"standard"
BODY_TYPE"PLUMBING"
HDL_TAP"TRUE";
"B \NAC \NWC"15;
"S \NAC"
BN"28"113;
%"TAP"
"1","(-1600,2550)","0","standard","I85";
;
CDS_LIB"standard"
BODY_TYPE"PLUMBING"
HDL_TAP"TRUE";
"B \NAC \NWC"15;
"S \NAC"
BN"29"114;
%"TAP"
"1","(-1600,2600)","0","standard","I86";
;
CDS_LIB"standard"
BODY_TYPE"PLUMBING"
HDL_TAP"TRUE";
"B \NAC \NWC"15;
"S \NAC"
BN"30"115;
%"TAP"
"1","(-1600,2850)","0","standard","I87";
;
CDS_LIB"standard"
BODY_TYPE"PLUMBING"
HDL_TAP"TRUE";
"B \NAC \NWC"10;
"S \NAC"
BN"2"119;
%"TAP"
"1","(-1600,2750)","0","standard","I88";
;
CDS_LIB"standard"
BODY_TYPE"PLUMBING"
HDL_TAP"TRUE";
"B \NAC \NWC"10;
"S \NAC"
BN"0"117;
%"TAP"
"1","(-1600,2650)","0","standard","I89";
;
CDS_LIB"standard"
BODY_TYPE"PLUMBING"
HDL_TAP"TRUE";
"B \NAC \NWC"15;
"S \NAC"
BN"31"116;
%"TAP"
"1","(-1600,2800)","0","standard","I90";
;
CDS_LIB"standard"
BODY_TYPE"PLUMBING"
HDL_TAP"TRUE";
"B \NAC \NWC"10;
"S \NAC"
BN"1"118;
%"TAP"
"1","(-1600,2950)","0","standard","I91";
;
CDS_LIB"standard"
BODY_TYPE"PLUMBING"
HDL_TAP"TRUE";
"B \NAC \NWC"10;
"S \NAC"
BN"4"121;
%"TAP"
"1","(-1600,2900)","0","standard","I92";
;
CDS_LIB"standard"
BODY_TYPE"PLUMBING"
HDL_TAP"TRUE";
"B \NAC \NWC"10;
"S \NAC"
BN"3"120;
%"TAP"
"1","(-1600,3000)","0","standard","I93";
;
CDS_LIB"standard"
BODY_TYPE"PLUMBING"
HDL_TAP"TRUE";
"B \NAC \NWC"10;
"S \NAC"
BN"5"122;
%"TAP"
"1","(-1600,3100)","0","standard","I94";
;
CDS_LIB"standard"
BODY_TYPE"PLUMBING"
HDL_TAP"TRUE";
"B \NAC \NWC"10;
"S \NAC"
BN"7"124;
%"TAP"
"1","(-1600,3050)","0","standard","I95";
;
CDS_LIB"standard"
BODY_TYPE"PLUMBING"
HDL_TAP"TRUE";
"B \NAC \NWC"10;
"S \NAC"
BN"6"123;
%"TAP"
"1","(-1600,3200)","0","standard","I96";
;
CDS_LIB"standard"
BODY_TYPE"PLUMBING"
HDL_TAP"TRUE";
"B \NAC \NWC"10;
"S \NAC"
BN"9"126;
%"TAP"
"1","(-1600,3150)","0","standard","I97";
;
CDS_LIB"standard"
BODY_TYPE"PLUMBING"
HDL_TAP"TRUE";
"B \NAC \NWC"10;
"S \NAC"
BN"8"125;
%"TAP"
"1","(-1600,3250)","0","standard","I98";
;
CDS_LIB"standard"
BODY_TYPE"PLUMBING"
HDL_TAP"TRUE";
"B \NAC \NWC"10;
"S \NAC"
BN"10"127;
%"TAP"
"1","(-1600,3300)","0","standard","I99";
;
CDS_LIB"standard"
BODY_TYPE"PLUMBING"
HDL_TAP"TRUE";
"B \NAC \NWC"10;
"S \NAC"
BN"11"128;
END.
